(kicad_pcb
	(version 20260206)
	(generator "pcbnew")
	(generator_version "10.0")
	(general
		(thickness 1.6)
		(legacy_teardrops no)
	)
	(paper "A4")
	(title_block
		(title "01162023_DA0F0TEBIF0_F0T_Expander_BD_F_brd_V02_OCP.brd")
		(comment 1 "Grand Teton / footprints 8886-8894 of 9728")
	)
	(layers
		(0 "F.Cu" signal "TOP")
		(4 "In1.Cu" signal "GND")
		(6 "In2.Cu" signal "VCC")
		(8 "In3.Cu" signal "VCC1")
		(10 "In4.Cu" signal "GND1")
		(12 "In5.Cu" signal "IN1")
		(14 "In6.Cu" signal "GND2")
		(16 "In7.Cu" signal "IN2")
		(18 "In8.Cu" signal "GND3")
		(20 "In9.Cu" signal "IN3")
		(22 "In10.Cu" signal "GND4")
		(24 "In11.Cu" signal "IN4")
		(26 "In12.Cu" signal "GND5")
		(28 "In13.Cu" signal "IN5")
		(30 "In14.Cu" signal "GND6")
		(32 "In15.Cu" signal "IN6")
		(34 "In16.Cu" signal "GND7")
		(2 "B.Cu" signal "BOTTOM")
		(9 "F.Adhes" user "F.Adhesive")
		(11 "B.Adhes" user "B.Adhesive")
		(13 "F.Paste" user "Package Geometry/Pastemask Top")
		(15 "B.Paste" user "Package Geometry/Pastemask Bottom")
		(5 "F.SilkS" user "Ref Des/Silkscreen Top")
		(7 "B.SilkS" user "Ref Des/Silkscreen Bottom")
		(1 "F.Mask" user "Board Geometry/Soldermask Top")
		(3 "B.Mask" user "Board Geometry/Soldermask Bottom")
		(17 "Dwgs.User" user "User.Drawings")
		(19 "Cmts.User" user "User.Comments")
		(21 "Eco1.User" user "User.Eco1")
		(23 "Eco2.User" user "User.Eco2")
		(25 "Edge.Cuts" user "Board Geometry/Outline")
		(27 "Margin" user)
		(31 "F.CrtYd" user "Package Geometry/Place Bound Top")
		(29 "B.CrtYd" user "Package Geometry/Place Bound Bottom")
		(35 "F.Fab" user "Ref Des/Assembly Top")
		(33 "B.Fab" user "Ref Des/Assembly Bottom")
	)
	(footprint ""
		(layer "B.Cu")
		(at 122.809762 -321.387978 -90)
		(property "Reference" "R6486"
			(at 0 0 90)
			(layer "B.SilkS")
			(hide yes)
			(effects
				(font
					(size 1.27 1.27)
				)
				(justify mirror)
			)
		)
		(property "Value" ""
			(at 0 0 90)
			(layer "B.Fab")
			(effects
				(font
					(size 1.27 1.27)
				)
				(justify mirror)
			)
		)
		(duplicate_pad_numbers_are_jumpers no)
		(fp_line
			(start -0.7874 0.4064)
			(end 0.7874 0.4064)
			(stroke
				(width 0.1524)
				(type default)
			)
			(layer "B.SilkS")
		)
		(fp_line
			(start 0.7874 0.4064)
			(end 0.7874 -0.4064)
			(stroke
				(width 0.1524)
				(type default)
			)
			(layer "B.SilkS")
		)
		(fp_line
			(start -0.7874 -0.4064)
			(end -0.7874 0.4064)
			(stroke
				(width 0.1524)
				(type default)
			)
			(layer "B.SilkS")
		)
		(fp_line
			(start 0.7874 -0.4064)
			(end -0.7874 -0.4064)
			(stroke
				(width 0.1524)
				(type default)
			)
			(layer "B.SilkS")
		)
		(fp_line
			(start -0.67945 0.3048)
			(end -0.120396 0.3048)
			(stroke
				(width 0.1)
				(type default)
			)
			(layer "B.Fab")
		)
		(fp_line
			(start -0.120396 0.3048)
			(end -0.120396 0.2794)
			(stroke
				(width 0.1)
				(type default)
			)
			(layer "B.Fab")
		)
		(fp_line
			(start 0.12065 0.3048)
			(end 0.67945 0.3048)
			(stroke
				(width 0.1)
				(type default)
			)
			(layer "B.Fab")
		)
		(fp_line
			(start 0.67945 0.3048)
			(end 0.67945 -0.305054)
			(stroke
				(width 0.1)
				(type default)
			)
			(layer "B.Fab")
		)
		(fp_line
			(start -0.120396 0.2794)
			(end 0.12065 0.2794)
			(stroke
				(width 0.1)
				(type default)
			)
			(layer "B.Fab")
		)
		(fp_line
			(start 0.12065 0.2794)
			(end 0.12065 0.3048)
			(stroke
				(width 0.1)
				(type default)
			)
			(layer "B.Fab")
		)
		(fp_line
			(start -0.12065 -0.2794)
			(end -0.12065 -0.3048)
			(stroke
				(width 0.1)
				(type default)
			)
			(layer "B.Fab")
		)
		(fp_line
			(start 0.12065 -0.2794)
			(end -0.12065 -0.2794)
			(stroke
				(width 0.1)
				(type default)
			)
			(layer "B.Fab")
		)
		(fp_line
			(start -0.67945 -0.3048)
			(end -0.67945 0.3048)
			(stroke
				(width 0.1)
				(type default)
			)
			(layer "B.Fab")
		)
		(fp_line
			(start -0.12065 -0.3048)
			(end -0.67945 -0.3048)
			(stroke
				(width 0.1)
				(type default)
			)
			(layer "B.Fab")
		)
		(fp_line
			(start 0.12065 -0.305054)
			(end 0.12065 -0.2794)
			(stroke
				(width 0.1)
				(type default)
			)
			(layer "B.Fab")
		)
		(fp_line
			(start 0.67945 -0.305054)
			(end 0.12065 -0.305054)
			(stroke
				(width 0.1)
				(type default)
			)
			(layer "B.Fab")
		)
		(pad "1" smd circle
			(at 0.40005 0 90)
			(size 0 0)
			(layers "B.Cu" "B.Mask" "B.Paste")
			(net "P0V8_SERDES_VDDA_PEX1")
		)
		(pad "2" smd circle
			(at -0.40005 0 90)
			(size 0 0)
			(layers "B.Cu" "B.Mask" "B.Paste")
			(net "P0V8_SERDES_VDDA_PEX1_C9")
		)
	)
	(footprint ""
		(layer "B.Cu")
		(at 279.974802 -296.64152 -90)
		(property "Reference" "C3389"
			(at 0 0 90)
			(layer "B.SilkS")
			(hide yes)
			(effects
				(font
					(size 1.27 1.27)
				)
				(justify mirror)
			)
		)
		(property "Value" ""
			(at 0 0 90)
			(layer "B.Fab")
			(effects
				(font
					(size 1.27 1.27)
				)
				(justify mirror)
			)
		)
		(duplicate_pad_numbers_are_jumpers no)
		(fp_line
			(start -0.299974 0.150114)
			(end 0.299974 0.150114)
			(stroke
				(width 0.1)
				(type default)
			)
			(layer "B.Fab")
		)
		(fp_line
			(start 0.299974 0.150114)
			(end 0.299974 -0.150114)
			(stroke
				(width 0.1)
				(type default)
			)
			(layer "B.Fab")
		)
		(fp_line
			(start -0.299974 -0.150114)
			(end -0.299974 0.150114)
			(stroke
				(width 0.1)
				(type default)
			)
			(layer "B.Fab")
		)
		(fp_line
			(start 0.299974 -0.150114)
			(end -0.299974 -0.150114)
			(stroke
				(width 0.1)
				(type default)
			)
			(layer "B.Fab")
		)
		(pad "1" smd rect
			(at 0.2667 0 90)
			(size 0.3048 0.381)
			(layers "B.Cu" "B.Mask" "B.Paste")
			(net "PCEPLL3_VDDA18_PEX2")
		)
		(pad "2" smd rect
			(at -0.2667 0 90)
			(size 0.3048 0.381)
			(layers "B.Cu" "B.Mask" "B.Paste")
			(net "GND")
		)
	)
	(footprint ""
		(layer "B.Cu")
		(at 294.690038 -202.16114 -90)
		(property "Reference" "R1042"
			(at 0 0 90)
			(layer "B.SilkS")
			(hide yes)
			(effects
				(font
					(size 1.27 1.27)
				)
				(justify mirror)
			)
		)
		(property "Value" ""
			(at 0 0 90)
			(layer "B.Fab")
			(effects
				(font
					(size 1.27 1.27)
				)
				(justify mirror)
			)
		)
		(duplicate_pad_numbers_are_jumpers no)
		(fp_line
			(start -0.7874 0.4064)
			(end 0.7874 0.4064)
			(stroke
				(width 0.1524)
				(type default)
			)
			(layer "B.SilkS")
		)
		(fp_line
			(start 0.7874 0.4064)
			(end 0.7874 -0.4064)
			(stroke
				(width 0.1524)
				(type default)
			)
			(layer "B.SilkS")
		)
		(fp_line
			(start -0.7874 -0.4064)
			(end -0.7874 0.4064)
			(stroke
				(width 0.1524)
				(type default)
			)
			(layer "B.SilkS")
		)
		(fp_line
			(start 0.7874 -0.4064)
			(end -0.7874 -0.4064)
			(stroke
				(width 0.1524)
				(type default)
			)
			(layer "B.SilkS")
		)
		(fp_line
			(start -0.67945 0.3048)
			(end -0.120396 0.3048)
			(stroke
				(width 0.1)
				(type default)
			)
			(layer "B.Fab")
		)
		(fp_line
			(start -0.120396 0.3048)
			(end -0.120396 0.2794)
			(stroke
				(width 0.1)
				(type default)
			)
			(layer "B.Fab")
		)
		(fp_line
			(start 0.12065 0.3048)
			(end 0.67945 0.3048)
			(stroke
				(width 0.1)
				(type default)
			)
			(layer "B.Fab")
		)
		(fp_line
			(start 0.67945 0.3048)
			(end 0.67945 -0.305054)
			(stroke
				(width 0.1)
				(type default)
			)
			(layer "B.Fab")
		)
		(fp_line
			(start -0.120396 0.2794)
			(end 0.12065 0.2794)
			(stroke
				(width 0.1)
				(type default)
			)
			(layer "B.Fab")
		)
		(fp_line
			(start 0.12065 0.2794)
			(end 0.12065 0.3048)
			(stroke
				(width 0.1)
				(type default)
			)
			(layer "B.Fab")
		)
		(fp_line
			(start -0.12065 -0.2794)
			(end -0.12065 -0.3048)
			(stroke
				(width 0.1)
				(type default)
			)
			(layer "B.Fab")
		)
		(fp_line
			(start 0.12065 -0.2794)
			(end -0.12065 -0.2794)
			(stroke
				(width 0.1)
				(type default)
			)
			(layer "B.Fab")
		)
		(fp_line
			(start -0.67945 -0.3048)
			(end -0.67945 0.3048)
			(stroke
				(width 0.1)
				(type default)
			)
			(layer "B.Fab")
		)
		(fp_line
			(start -0.12065 -0.3048)
			(end -0.67945 -0.3048)
			(stroke
				(width 0.1)
				(type default)
			)
			(layer "B.Fab")
		)
		(fp_line
			(start 0.12065 -0.305054)
			(end 0.12065 -0.2794)
			(stroke
				(width 0.1)
				(type default)
			)
			(layer "B.Fab")
		)
		(fp_line
			(start 0.67945 -0.305054)
			(end 0.12065 -0.305054)
			(stroke
				(width 0.1)
				(type default)
			)
			(layer "B.Fab")
		)
		(pad "1" smd circle
			(at 0.40005 0 90)
			(size 0 0)
			(layers "B.Cu" "B.Mask" "B.Paste")
			(net "GND")
		)
		(pad "2" smd circle
			(at -0.40005 0 90)
			(size 0 0)
			(layers "B.Cu" "B.Mask" "B.Paste")
			(net "SPI_BIC1_CLK_LS23_DIR2")
		)
	)
	(footprint ""
		(layer "B.Cu")
		(at 54.899814 -288.299906 90)
		(property "Reference" "C2932"
			(at 0 0 90)
			(layer "B.SilkS")
			(hide yes)
			(effects
				(font
					(size 1.27 1.27)
				)
				(justify mirror)
			)
		)
		(property "Value" ""
			(at 0 0 90)
			(layer "B.Fab")
			(effects
				(font
					(size 1.27 1.27)
				)
				(justify mirror)
			)
		)
		(duplicate_pad_numbers_are_jumpers no)
		(fp_line
			(start 0.299974 -0.150114)
			(end -0.299974 -0.150114)
			(stroke
				(width 0.1)
				(type default)
			)
			(layer "B.Fab")
		)
		(fp_line
			(start -0.299974 -0.150114)
			(end -0.299974 0.150114)
			(stroke
				(width 0.1)
				(type default)
			)
			(layer "B.Fab")
		)
		(fp_line
			(start 0.299974 0.150114)
			(end 0.299974 -0.150114)
			(stroke
				(width 0.1)
				(type default)
			)
			(layer "B.Fab")
		)
		(fp_line
			(start -0.299974 0.150114)
			(end 0.299974 0.150114)
			(stroke
				(width 0.1)
				(type default)
			)
			(layer "B.Fab")
		)
		(pad "1" smd rect
			(at 0.2667 0 270)
			(size 0.3048 0.381)
			(layers "B.Cu" "B.Mask" "B.Paste")
			(net "P1V25_PEX0")
		)
		(pad "2" smd rect
			(at -0.2667 0 270)
			(size 0.3048 0.381)
			(layers "B.Cu" "B.Mask" "B.Paste")
			(net "GND")
		)
	)
	(footprint ""
		(layer "B.Cu")
		(at 219.98432 -292.62832)
		(property "Reference" "PC992"
			(at 0 0 0)
			(layer "B.SilkS")
			(hide yes)
			(effects
				(font
					(size 1.27 1.27)
				)
				(justify mirror)
			)
		)
		(property "Value" ""
			(at 0 0 0)
			(layer "B.Fab")
			(effects
				(font
					(size 1.27 1.27)
				)
				(justify mirror)
			)
		)
		(duplicate_pad_numbers_are_jumpers no)
		(fp_line
			(start -1.524 -0.762)
			(end -1.524 0.762)
			(stroke
				(width 0.1524)
				(type default)
			)
			(layer "B.SilkS")
		)
		(fp_line
			(start -1.524 0.762)
			(end 1.524 0.762)
			(stroke
				(width 0.1524)
				(type default)
			)
			(layer "B.SilkS")
		)
		(fp_line
			(start 1.524 -0.762)
			(end -1.524 -0.762)
			(stroke
				(width 0.1524)
				(type default)
			)
			(layer "B.SilkS")
		)
		(fp_line
			(start 1.524 0.762)
			(end 1.524 -0.762)
			(stroke
				(width 0.1524)
				(type default)
			)
			(layer "B.SilkS")
		)
		(fp_line
			(start -1.1049 -0.724916)
			(end 1.1049 -0.724916)
			(stroke
				(width 0.1)
				(type default)
			)
			(layer "B.Fab")
		)
		(fp_line
			(start -1.1049 0.724916)
			(end -1.1049 -0.724916)
			(stroke
				(width 0.1)
				(type default)
			)
			(layer "B.Fab")
		)
		(fp_line
			(start 1.1049 -0.724916)
			(end 1.1049 0.724916)
			(stroke
				(width 0.1)
				(type default)
			)
			(layer "B.Fab")
		)
		(fp_line
			(start 1.1049 0.724916)
			(end -1.1049 0.724916)
			(stroke
				(width 0.1)
				(type default)
			)
			(layer "B.Fab")
		)
		(pad "1" smd rect
			(at 0.889 0)
			(size 1.016 1.27)
			(layers "B.Cu" "B.Mask" "B.Paste")
			(net "P1V25_PEX1_R")
		)
		(pad "2" smd rect
			(at -0.889 0)
			(size 1.016 1.27)
			(layers "B.Cu" "B.Mask" "B.Paste")
			(net "GND")
		)
	)
	(footprint ""
		(layer "B.Cu")
		(at 187.386214 -117.66169)
		(property "Reference" "R156"
			(at 0 0 0)
			(layer "B.SilkS")
			(hide yes)
			(effects
				(font
					(size 1.27 1.27)
				)
				(justify mirror)
			)
		)
		(property "Value" ""
			(at 0 0 0)
			(layer "B.Fab")
			(effects
				(font
					(size 1.27 1.27)
				)
				(justify mirror)
			)
		)
		(duplicate_pad_numbers_are_jumpers no)
		(fp_line
			(start -0.7874 -0.4064)
			(end -0.7874 0.4064)
			(stroke
				(width 0.1524)
				(type default)
			)
			(layer "B.SilkS")
		)
		(fp_line
			(start -0.7874 0.4064)
			(end 0.7874 0.4064)
			(stroke
				(width 0.1524)
				(type default)
			)
			(layer "B.SilkS")
		)
		(fp_line
			(start 0.7874 -0.4064)
			(end -0.7874 -0.4064)
			(stroke
				(width 0.1524)
				(type default)
			)
			(layer "B.SilkS")
		)
		(fp_line
			(start 0.7874 0.4064)
			(end 0.7874 -0.4064)
			(stroke
				(width 0.1524)
				(type default)
			)
			(layer "B.SilkS")
		)
		(fp_line
			(start -0.67945 -0.3048)
			(end -0.67945 0.3048)
			(stroke
				(width 0.1)
				(type default)
			)
			(layer "B.Fab")
		)
		(fp_line
			(start -0.67945 0.3048)
			(end -0.120396 0.3048)
			(stroke
				(width 0.1)
				(type default)
			)
			(layer "B.Fab")
		)
		(fp_line
			(start -0.12065 -0.3048)
			(end -0.67945 -0.3048)
			(stroke
				(width 0.1)
				(type default)
			)
			(layer "B.Fab")
		)
		(fp_line
			(start -0.12065 -0.2794)
			(end -0.12065 -0.3048)
			(stroke
				(width 0.1)
				(type default)
			)
			(layer "B.Fab")
		)
		(fp_line
			(start -0.120396 0.2794)
			(end 0.12065 0.2794)
			(stroke
				(width 0.1)
				(type default)
			)
			(layer "B.Fab")
		)
		(fp_line
			(start -0.120396 0.3048)
			(end -0.120396 0.2794)
			(stroke
				(width 0.1)
				(type default)
			)
			(layer "B.Fab")
		)
		(fp_line
			(start 0.12065 -0.305054)
			(end 0.12065 -0.2794)
			(stroke
				(width 0.1)
				(type default)
			)
			(layer "B.Fab")
		)
		(fp_line
			(start 0.12065 -0.2794)
			(end -0.12065 -0.2794)
			(stroke
				(width 0.1)
				(type default)
			)
			(layer "B.Fab")
		)
		(fp_line
			(start 0.12065 0.2794)
			(end 0.12065 0.3048)
			(stroke
				(width 0.1)
				(type default)
			)
			(layer "B.Fab")
		)
		(fp_line
			(start 0.12065 0.3048)
			(end 0.67945 0.3048)
			(stroke
				(width 0.1)
				(type default)
			)
			(layer "B.Fab")
		)
		(fp_line
			(start 0.67945 -0.305054)
			(end 0.12065 -0.305054)
			(stroke
				(width 0.1)
				(type default)
			)
			(layer "B.Fab")
		)
		(fp_line
			(start 0.67945 0.3048)
			(end 0.67945 -0.305054)
			(stroke
				(width 0.1)
				(type default)
			)
			(layer "B.Fab")
		)
		(pad "1" smd circle
			(at 0.40005 0 180)
			(size 0 0)
			(layers "B.Cu" "B.Mask" "B.Paste")
			(net "NIC3_AUX_PWR_EN_R")
		)
		(pad "2" smd circle
			(at -0.40005 0 180)
			(size 0 0)
			(layers "B.Cu" "B.Mask" "B.Paste")
			(net "NIC3_AUX_PWR_EN")
		)
	)
	(footprint ""
		(layer "B.Cu")
		(at 165.655244 -151.9936)
		(property "Reference" "R120"
			(at 0 0 0)
			(layer "B.SilkS")
			(hide yes)
			(effects
				(font
					(size 1.27 1.27)
				)
				(justify mirror)
			)
		)
		(property "Value" ""
			(at 0 0 0)
			(layer "B.Fab")
			(effects
				(font
					(size 1.27 1.27)
				)
				(justify mirror)
			)
		)
		(duplicate_pad_numbers_are_jumpers no)
		(fp_line
			(start -0.7874 -0.4064)
			(end -0.7874 0.4064)
			(stroke
				(width 0.1524)
				(type default)
			)
			(layer "B.SilkS")
		)
		(fp_line
			(start -0.7874 0.4064)
			(end 0.7874 0.4064)
			(stroke
				(width 0.1524)
				(type default)
			)
			(layer "B.SilkS")
		)
		(fp_line
			(start 0.7874 -0.4064)
			(end -0.7874 -0.4064)
			(stroke
				(width 0.1524)
				(type default)
			)
			(layer "B.SilkS")
		)
		(fp_line
			(start 0.7874 0.4064)
			(end 0.7874 -0.4064)
			(stroke
				(width 0.1524)
				(type default)
			)
			(layer "B.SilkS")
		)
		(fp_line
			(start -0.67945 -0.3048)
			(end -0.67945 0.3048)
			(stroke
				(width 0.1)
				(type default)
			)
			(layer "B.Fab")
		)
		(fp_line
			(start -0.67945 0.3048)
			(end -0.120396 0.3048)
			(stroke
				(width 0.1)
				(type default)
			)
			(layer "B.Fab")
		)
		(fp_line
			(start -0.12065 -0.3048)
			(end -0.67945 -0.3048)
			(stroke
				(width 0.1)
				(type default)
			)
			(layer "B.Fab")
		)
		(fp_line
			(start -0.12065 -0.2794)
			(end -0.12065 -0.3048)
			(stroke
				(width 0.1)
				(type default)
			)
			(layer "B.Fab")
		)
		(fp_line
			(start -0.120396 0.2794)
			(end 0.12065 0.2794)
			(stroke
				(width 0.1)
				(type default)
			)
			(layer "B.Fab")
		)
		(fp_line
			(start -0.120396 0.3048)
			(end -0.120396 0.2794)
			(stroke
				(width 0.1)
				(type default)
			)
			(layer "B.Fab")
		)
		(fp_line
			(start 0.12065 -0.305054)
			(end 0.12065 -0.2794)
			(stroke
				(width 0.1)
				(type default)
			)
			(layer "B.Fab")
		)
		(fp_line
			(start 0.12065 -0.2794)
			(end -0.12065 -0.2794)
			(stroke
				(width 0.1)
				(type default)
			)
			(layer "B.Fab")
		)
		(fp_line
			(start 0.12065 0.2794)
			(end 0.12065 0.3048)
			(stroke
				(width 0.1)
				(type default)
			)
			(layer "B.Fab")
		)
		(fp_line
			(start 0.12065 0.3048)
			(end 0.67945 0.3048)
			(stroke
				(width 0.1)
				(type default)
			)
			(layer "B.Fab")
		)
		(fp_line
			(start 0.67945 -0.305054)
			(end 0.12065 -0.305054)
			(stroke
				(width 0.1)
				(type default)
			)
			(layer "B.Fab")
		)
		(fp_line
			(start 0.67945 0.3048)
			(end 0.67945 -0.305054)
			(stroke
				(width 0.1)
				(type default)
			)
			(layer "B.Fab")
		)
		(pad "1" smd circle
			(at 0.40005 0 180)
			(size 0 0)
			(layers "B.Cu" "B.Mask" "B.Paste")
			(net "NCSI_NIC2_TXD0")
		)
		(pad "2" smd circle
			(at -0.40005 0 180)
			(size 0 0)
			(layers "B.Cu" "B.Mask" "B.Paste")
			(net "GND")
		)
	)
	(footprint ""
		(layer "B.Cu")
		(at 67.249802 -292.099746 90)
		(property "Reference" "C1191"
			(at 0 0 90)
			(layer "B.SilkS")
			(hide yes)
			(effects
				(font
					(size 1.27 1.27)
				)
				(justify mirror)
			)
		)
		(property "Value" ""
			(at 0 0 90)
			(layer "B.Fab")
			(effects
				(font
					(size 1.27 1.27)
				)
				(justify mirror)
			)
		)
		(duplicate_pad_numbers_are_jumpers no)
		(fp_line
			(start 0.299974 -0.150114)
			(end -0.299974 -0.150114)
			(stroke
				(width 0.1)
				(type default)
			)
			(layer "B.Fab")
		)
		(fp_line
			(start -0.299974 -0.150114)
			(end -0.299974 0.150114)
			(stroke
				(width 0.1)
				(type default)
			)
			(layer "B.Fab")
		)
		(fp_line
			(start 0.299974 0.150114)
			(end 0.299974 -0.150114)
			(stroke
				(width 0.1)
				(type default)
			)
			(layer "B.Fab")
		)
		(fp_line
			(start -0.299974 0.150114)
			(end 0.299974 0.150114)
			(stroke
				(width 0.1)
				(type default)
			)
			(layer "B.Fab")
		)
		(pad "1" smd rect
			(at 0.2667 0 270)
			(size 0.3048 0.381)
			(layers "B.Cu" "B.Mask" "B.Paste")
			(net "P0V8_SERDES_VDDA_PEX0")
		)
		(pad "2" smd rect
			(at -0.2667 0 270)
			(size 0.3048 0.381)
			(layers "B.Cu" "B.Mask" "B.Paste")
			(net "GND")
		)
	)
	(footprint ""
		(layer "B.Cu")
		(at 288.99993 -290.199826 90)
		(property "Reference" "C1721"
			(at 0 0 90)
			(layer "B.SilkS")
			(hide yes)
			(effects
				(font
					(size 1.27 1.27)
				)
				(justify mirror)
			)
		)
		(property "Value" ""
			(at 0 0 90)
			(layer "B.Fab")
			(effects
				(font
					(size 1.27 1.27)
				)
				(justify mirror)
			)
		)
		(duplicate_pad_numbers_are_jumpers no)
		(fp_line
			(start 0.299974 -0.150114)
			(end -0.299974 -0.150114)
			(stroke
				(width 0.1)
				(type default)
			)
			(layer "B.Fab")
		)
		(fp_line
			(start -0.299974 -0.150114)
			(end -0.299974 0.150114)
			(stroke
				(width 0.1)
				(type default)
			)
			(layer "B.Fab")
		)
		(fp_line
			(start 0.299974 0.150114)
			(end 0.299974 -0.150114)
			(stroke
				(width 0.1)
				(type default)
			)
			(layer "B.Fab")
		)
		(fp_line
			(start -0.299974 0.150114)
			(end 0.299974 0.150114)
			(stroke
				(width 0.1)
				(type default)
			)
			(layer "B.Fab")
		)
		(pad "1" smd rect
			(at 0.2667 0 270)
			(size 0.3048 0.381)
			(layers "B.Cu" "B.Mask" "B.Paste")
			(net "P0V8_SERDES_VDDA_PEX2")
		)
		(pad "2" smd rect
			(at -0.2667 0 270)
			(size 0.3048 0.381)
			(layers "B.Cu" "B.Mask" "B.Paste")
			(net "GND")
		)
	)
)
